# BASEBOARD_FAB2 (Tioga Pass) — schematic netlist excerpt (pin names and nets, part order shuffled) for the footprints in the layout excerpt that follows; sources: Cadence DE-HDL packaged netlist, KiCad conversion of Wiwynn_Tioga_Pass_MB.brd

R2T37  RES  200.0 1% CHIP  pkg 0402  page 92 : A = PVCCIO_CPU0 ; B = H_CPU_ERR2_G_R_N
R4G25  RES  0.0 5% CHIP  pkg 0402  page 233 : A = GND ; B = AGND_PVPP_GHJ
R5D3  RES  240 1.0% CHIP  pkg 0402  page 90 : A = PVCCIO_CPU0 ; B = PU_CPU0_FRMAGENT

(kicad_pcb
	(version 20260206)
	(generator "pcbnew")
	(generator_version "10.0")
	(general
		(thickness 1.6)
		(legacy_teardrops no)
	)
	(paper "A4")
	(title_block
		(title "Wiwynn_Tioga_Pass_MB.brd")
		(comment 1 "Tioga Pass / footprints 1502-1504 of 4770")
	)
	(layers
		(0 "F.Cu" signal "TOP")
		(4 "In1.Cu" signal "L2GND")
		(6 "In2.Cu" signal "L3")
		(8 "In3.Cu" signal "L4GND")
		(10 "In4.Cu" signal "L5")
		(12 "In5.Cu" signal "L6GND")
		(14 "In6.Cu" signal "L7VCC")
		(16 "In7.Cu" signal "L8VCC")
		(18 "In8.Cu" signal "L9GND")
		(20 "In9.Cu" signal "L10")
		(22 "In10.Cu" signal "L11GND")
		(24 "In11.Cu" signal "L12")
		(26 "In12.Cu" signal "L13GND")
		(2 "B.Cu" signal "BOTTOM")
		(9 "F.Adhes" user "F.Adhesive")
		(11 "B.Adhes" user "B.Adhesive")
		(13 "F.Paste" user "Package Geometry/Pastemask Top")
		(15 "B.Paste" user "Package Geometry/Pastemask Bottom")
		(5 "F.SilkS" user "Ref Des/Silkscreen Top")
		(7 "B.SilkS" user "Ref Des/Silkscreen Bottom")
		(1 "F.Mask" user "Board Geometry/Soldermask Top")
		(3 "B.Mask" user "Board Geometry/Soldermask Bottom")
		(17 "Dwgs.User" user "User.Drawings")
		(19 "Cmts.User" user "User.Comments")
		(21 "Eco1.User" user "User.Eco1")
		(23 "Eco2.User" user "User.Eco2")
		(25 "Edge.Cuts" user "Board Geometry/Outline")
		(27 "Margin" user)
		(31 "F.CrtYd" user "Package Geometry/Place Bound Top")
		(29 "B.CrtYd" user "Package Geometry/Place Bound Bottom")
		(35 "F.Fab" user "Ref Des/Assembly Top")
		(33 "B.Fab" user "Ref Des/Assembly Bottom")
	)
	(footprint ""
		(layer "F.Cu")
		(at 383.660904 -76.026264 180)
		(property "Reference" "R2T37"
			(at 0 0 180)
			(layer "F.SilkS")
			(hide yes)
			(effects
				(font
					(size 1.27 1.27)
				)
			)
		)
		(property "Value" ""
			(at 0 0 180)
			(layer "F.Fab")
			(effects
				(font
					(size 1.27 1.27)
				)
			)
		)
		(duplicate_pad_numbers_are_jumpers no)
		(fp_poly
			(pts
				(xy -0.2794 -0.1016) (xy 0.2794 -0.1016) (xy 0.2794 0.9906) (xy -0.2794 0.9906)
			)
			(stroke
				(width 0)
				(type default)
			)
			(fill no)
			(layer "F.CrtYd")
		)
		(fp_line
			(start 0.2794 0.9906)
			(end 0.2794 -0.1016)
			(stroke
				(width 0.1)
				(type default)
			)
			(layer "F.Fab")
		)
		(fp_line
			(start 0.2794 -0.1016)
			(end -0.2794 -0.1016)
			(stroke
				(width 0.1)
				(type default)
			)
			(layer "F.Fab")
		)
		(fp_line
			(start -0.2794 0.9906)
			(end 0.2794 0.9906)
			(stroke
				(width 0.1)
				(type default)
			)
			(layer "F.Fab")
		)
		(fp_line
			(start -0.2794 -0.1016)
			(end -0.2794 0.9906)
			(stroke
				(width 0.1)
				(type default)
			)
			(layer "F.Fab")
		)
		(pad "1" smd rect
			(at 0 0 180)
			(size 0.508 0.508)
			(layers "F.Cu" "F.Mask" "F.Paste")
			(net "PVCCIO_CPU0")
		)
		(pad "2" smd rect
			(at 0 0.889 180)
			(size 0.508 0.508)
			(layers "F.Cu" "F.Mask" "F.Paste")
			(net "H_CPU_ERR2_G_R_N")
		)
		(zone
			(layer "F.Cu")
			(hatch none 0.5)
			(connect_pads
				(clearance 0)
			)
			(min_thickness 0.25)
			(keepout
				(tracks not_allowed)
				(vias allowed)
				(pads allowed)
				(copperpour not_allowed)
				(footprints allowed)
			)
			(placement
				(enabled no)
				(sheetname "")
			)
			(fill
				(thermal_gap 0.5)
				(thermal_bridge_width 0.5)
				(island_removal_mode 0)
			)
			(polygon
				(pts
					(xy 383.914904 -76.661264) (xy 383.406904 -76.661264) (xy 383.406904 -76.280264) (xy 383.914904 -76.280264)
				)
			)
		)
		(zone
			(layer "F.Cu")
			(hatch none 0.5)
			(connect_pads
				(clearance 0)
			)
			(min_thickness 0.25)
			(keepout
				(tracks allowed)
				(vias not_allowed)
				(pads allowed)
				(copperpour not_allowed)
				(footprints allowed)
			)
			(placement
				(enabled no)
				(sheetname "")
			)
			(fill
				(thermal_gap 0.5)
				(thermal_bridge_width 0.5)
				(island_removal_mode 0)
			)
			(polygon
				(pts
					(xy 383.914904 -76.280264) (xy 383.406904 -76.280264) (xy 383.406904 -76.661264) (xy 383.914904 -76.661264)
				)
			)
		)
	)
	(footprint ""
		(layer "F.Cu")
		(at 274.447 -69.977)
		(property "Reference" "R5D3"
			(at 0 0 0)
			(layer "F.SilkS")
			(hide yes)
			(effects
				(font
					(size 1.27 1.27)
				)
			)
		)
		(property "Value" ""
			(at 0 0 0)
			(layer "F.Fab")
			(effects
				(font
					(size 1.27 1.27)
				)
			)
		)
		(duplicate_pad_numbers_are_jumpers no)
		(fp_poly
			(pts
				(xy -0.2794 -0.1016) (xy 0.2794 -0.1016) (xy 0.2794 0.9906) (xy -0.2794 0.9906)
			)
			(stroke
				(width 0)
				(type default)
			)
			(fill no)
			(layer "F.CrtYd")
		)
		(fp_line
			(start -0.2794 -0.1016)
			(end -0.2794 0.9906)
			(stroke
				(width 0.1)
				(type default)
			)
			(layer "F.Fab")
		)
		(fp_line
			(start -0.2794 0.9906)
			(end 0.2794 0.9906)
			(stroke
				(width 0.1)
				(type default)
			)
			(layer "F.Fab")
		)
		(fp_line
			(start 0.2794 -0.1016)
			(end -0.2794 -0.1016)
			(stroke
				(width 0.1)
				(type default)
			)
			(layer "F.Fab")
		)
		(fp_line
			(start 0.2794 0.9906)
			(end 0.2794 -0.1016)
			(stroke
				(width 0.1)
				(type default)
			)
			(layer "F.Fab")
		)
		(pad "1" smd rect
			(at 0 0)
			(size 0.508 0.508)
			(layers "F.Cu" "F.Mask" "F.Paste")
			(net "PVCCIO_CPU0")
		)
		(pad "2" smd rect
			(at 0 0.889)
			(size 0.508 0.508)
			(layers "F.Cu" "F.Mask" "F.Paste")
			(net "PU_CPU0_FRMAGENT")
		)
		(zone
			(layer "F.Cu")
			(hatch none 0.5)
			(connect_pads
				(clearance 0)
			)
			(min_thickness 0.25)
			(keepout
				(tracks allowed)
				(vias not_allowed)
				(pads allowed)
				(copperpour not_allowed)
				(footprints allowed)
			)
			(placement
				(enabled no)
				(sheetname "")
			)
			(fill
				(thermal_gap 0.5)
				(thermal_bridge_width 0.5)
				(island_removal_mode 0)
			)
			(polygon
				(pts
					(xy 274.193 -69.723) (xy 274.701 -69.723) (xy 274.701 -69.342) (xy 274.193 -69.342)
				)
			)
		)
		(zone
			(layer "F.Cu")
			(hatch none 0.5)
			(connect_pads
				(clearance 0)
			)
			(min_thickness 0.25)
			(keepout
				(tracks not_allowed)
				(vias allowed)
				(pads allowed)
				(copperpour not_allowed)
				(footprints allowed)
			)
			(placement
				(enabled no)
				(sheetname "")
			)
			(fill
				(thermal_gap 0.5)
				(thermal_bridge_width 0.5)
				(island_removal_mode 0)
			)
			(polygon
				(pts
					(xy 274.193 -69.342) (xy 274.701 -69.342) (xy 274.701 -69.723) (xy 274.193 -69.723)
				)
			)
		)
	)
	(footprint ""
		(layer "F.Cu")
		(at 174.4218 -6.2103 180)
		(property "Reference" "R4G25"
			(at 0 0 180)
			(layer "F.SilkS")
			(hide yes)
			(effects
				(font
					(size 1.27 1.27)
				)
			)
		)
		(property "Value" ""
			(at 0 0 180)
			(layer "F.Fab")
			(effects
				(font
					(size 1.27 1.27)
				)
			)
		)
		(duplicate_pad_numbers_are_jumpers no)
		(fp_rect
			(start 0.2794 -0.1016)
			(end -0.2794 0.9906)
			(stroke
				(width 0)
				(type default)
			)
			(fill no)
			(layer "F.CrtYd")
		)
		(fp_line
			(start 0.2794 0.9906)
			(end 0.2794 -0.1016)
			(stroke
				(width 0.1)
				(type default)
			)
			(layer "F.Fab")
		)
		(fp_line
			(start 0.2794 -0.1016)
			(end -0.2794 -0.1016)
			(stroke
				(width 0.1)
				(type default)
			)
			(layer "F.Fab")
		)
		(fp_line
			(start -0.2794 0.9906)
			(end 0.2794 0.9906)
			(stroke
				(width 0.1)
				(type default)
			)
			(layer "F.Fab")
		)
		(fp_line
			(start -0.2794 -0.1016)
			(end -0.2794 0.9906)
			(stroke
				(width 0.1)
				(type default)
			)
			(layer "F.Fab")
		)
		(pad "1" smd rect
			(at 0 0 180)
			(size 0.508 0.508)
			(layers "F.Cu" "F.Mask" "F.Paste")
			(net "GND")
		)
		(pad "2" smd rect
			(at 0 0.889 180)
			(size 0.508 0.508)
			(layers "F.Cu" "F.Mask" "F.Paste")
			(net "AGND_PVPP_GHJ")
		)
		(zone
			(layer "F.Cu")
			(hatch none 0.5)
			(connect_pads
				(clearance 0)
			)
			(min_thickness 0.25)
			(keepout
				(tracks allowed)
				(vias not_allowed)
				(pads allowed)
				(copperpour not_allowed)
				(footprints allowed)
			)
			(placement
				(enabled no)
				(sheetname "")
			)
			(fill
				(thermal_gap 0.5)
				(thermal_bridge_width 0.5)
				(island_removal_mode 0)
			)
			(polygon
				(pts
					(xy 174.1678 -6.4643) (xy 174.6758 -6.4643) (xy 174.6758 -6.8453) (xy 174.1678 -6.8453)
				)
			)
		)
		(zone
			(layer "F.Cu")
			(hatch none 0.5)
			(connect_pads
				(clearance 0)
			)
			(min_thickness 0.25)
			(keepout
				(tracks not_allowed)
				(vias allowed)
				(pads allowed)
				(copperpour not_allowed)
				(footprints allowed)
			)
			(placement
				(enabled no)
				(sheetname "")
			)
			(fill
				(thermal_gap 0.5)
				(thermal_bridge_width 0.5)
				(island_removal_mode 0)
			)
			(polygon
				(pts
					(xy 174.1678 -6.4643) (xy 174.6758 -6.4643) (xy 174.6758 -6.8453) (xy 174.1678 -6.8453)
				)
			)
		)
	)
)
